(kicad_pcb
	(version 20241229)
	(generator "pcbnew")
	(generator_version "9.0")
	(general
		(thickness 1.6296)
		(legacy_teardrops no)
	)
	(paper "A3")
	(title_block
		(title "Thunderbolt to 10GbE adapter")
		(date "2026-04-21")
		(rev "1.1.0")
		(company "Antmicro Ltd")
		(comment 1 "www.antmicro.com")
		(comment 9 "footprints 431-435 of 703")
	)
	(layers
		(0 "F.Cu" signal)
		(4 "In1.Cu" signal)
		(6 "In2.Cu" signal)
		(8 "In3.Cu" signal)
		(10 "In4.Cu" signal)
		(12 "In5.Cu" signal)
		(14 "In6.Cu" signal)
		(2 "B.Cu" signal)
		(9 "F.Adhes" user "F.Adhesive")
		(11 "B.Adhes" user "B.Adhesive")
		(13 "F.Paste" user)
		(15 "B.Paste" user)
		(5 "F.SilkS" user "F.Silkscreen")
		(7 "B.SilkS" user "B.Silkscreen")
		(1 "F.Mask" user)
		(3 "B.Mask" user)
		(17 "Dwgs.User" user "User.Drawings")
		(19 "Cmts.User" user "User.Comments")
		(21 "Eco1.User" user "User.Eco1")
		(23 "Eco2.User" user "User.Eco2")
		(25 "Edge.Cuts" user)
		(27 "Margin" user)
		(31 "F.CrtYd" user "F.Courtyard")
		(29 "B.CrtYd" user "B.Courtyard")
		(35 "F.Fab" user)
		(33 "B.Fab" user)
	)
	(footprint "antmicro-footprints:R_0402_1005Metric"
		(layer "B.Cu")
		(at 132.875002 131.099998 90)
		(descr "Resistor SMD 0402")
		(tags "resistor SMD 0402")
		(property "Reference" "R4"
			(at 8.35 19.525001 270)
			(layer "B.SilkS")
			(effects
				(font
					(size 0.7 0.7)
					(thickness 0.15)
				)
				(justify mirror)
			)
		)
		(property "Value" "R_100k_0402"
			(at -1.011843 -1.772047 270)
			(layer "B.Fab")
			(effects
				(font
					(size 0.7 0.7)
					(thickness 0.15)
				)
				(justify left bottom mirror)
			)
		)
		(property "Datasheet" "https://www.bourns.com/docs/product-datasheets/cr.pdf"
			(at 0 0 270)
			(layer "B.Fab")
			(hide yes)
			(effects
				(font
					(size 1.27 1.27)
					(thickness 0.15)
				)
				(justify mirror)
			)
		)
		(property "Description" "SMD Chip Resistor, 100 kohm, ± 1%, 62.5 mW, 0402 [1005 Metric], Thick Film, General Purpose"
			(at 0 0 270)
			(layer "B.Fab")
			(hide yes)
			(effects
				(font
					(size 1.27 1.27)
					(thickness 0.15)
				)
				(justify mirror)
			)
		)
		(property "MPN" "CR0402-FX-1003GLF"
			(at 0 0 90)
			(unlocked yes)
			(layer "B.Fab")
			(hide yes)
			(effects
				(font
					(size 1 1)
					(thickness 0.15)
				)
				(justify mirror)
			)
		)
		(property "Manufacturer" "Bourns"
			(at 0 0 90)
			(unlocked yes)
			(layer "B.Fab")
			(hide yes)
			(effects
				(font
					(size 1 1)
					(thickness 0.15)
				)
				(justify mirror)
			)
		)
		(property "License" "Apache-2.0"
			(at 0 0 90)
			(unlocked yes)
			(layer "B.Fab")
			(hide yes)
			(effects
				(font
					(size 1 1)
					(thickness 0.15)
				)
				(justify mirror)
			)
		)
		(property "Val" "100k"
			(at 0 0 90)
			(unlocked yes)
			(layer "B.Fab")
			(hide yes)
			(effects
				(font
					(size 1 1)
					(thickness 0.15)
				)
				(justify mirror)
			)
		)
		(property "Tolerance" "1%"
			(at 0 0 90)
			(unlocked yes)
			(layer "B.Fab")
			(hide yes)
			(effects
				(font
					(size 1 1)
					(thickness 0.15)
				)
				(justify mirror)
			)
		)
		(property "Author" "Antmicro"
			(at 0 0 90)
			(unlocked yes)
			(layer "B.Fab")
			(hide yes)
			(effects
				(font
					(size 1 1)
					(thickness 0.15)
				)
				(justify mirror)
			)
		)
		(sheetname "/PD and TB DC-DC/")
		(sheetfile "PD_and_TB_DC_DC.kicad_sch")
		(attr smd)
		(fp_rect
			(start -0.925 0.47)
			(end 0.925 -0.47)
			(stroke
				(width 0.05)
				(type default)
			)
			(fill no)
			(layer "B.CrtYd")
		)
		(fp_rect
			(start -0.5 0.25)
			(end 0.5 -0.25)
			(stroke
				(width 0.15)
				(type solid)
			)
			(fill no)
			(layer "B.Fab")
		)
		(fp_text user "License: Apache-2.0"
			(at -0.95 -5.169 270)
			(layer "B.Fab")
			(effects
				(font
					(size 0.7 0.7)
					(thickness 0.15)
				)
				(justify left bottom mirror)
			)
		)
		(fp_text user "${REFERENCE}"
			(at -0.95 -3.168 270)
			(layer "B.Fab")
			(effects
				(font
					(size 0.7 0.7)
					(thickness 0.15)
				)
				(justify left bottom mirror)
			)
		)
		(fp_text user "Author: Antmicro"
			(at -0.95 -4.169 270)
			(layer "B.Fab")
			(effects
				(font
					(size 0.7 0.7)
					(thickness 0.15)
				)
				(justify left bottom mirror)
			)
		)
		(pad "1" smd roundrect
			(at -0.48 0 90)
			(size 0.59 0.64)
			(layers "B.Cu" "B.Mask" "B.Paste")
			(roundrect_rratio 0.25)
			(net 79 "/PD and TB DC-DC/AUX.-")
			(pintype "passive")
		)
		(pad "2" smd roundrect
			(at 0.48 0 90)
			(size 0.59 0.64)
			(layers "B.Cu" "B.Mask" "B.Paste")
			(roundrect_rratio 0.25)
			(net 304 "/PD and TB DC-DC/TPS_3V3")
			(pintype "passive")
		)
	)
	(footprint "antmicro-footprints:C_0402_1005Metric"
		(layer "B.Cu")
		(at 157.961866 85.035118 180)
		(descr "Capacitor SMD 0402")
		(tags "capacitor SMD 0402")
		(property "Reference" "C204"
			(at -20.793134 -9.464883 0)
			(layer "B.SilkS")
			(effects
				(font
					(size 0.7 0.7)
					(thickness 0.15)
				)
				(justify mirror)
			)
		)
		(property "Value" "C_1u_25V_0402"
			(at -1.022927 -2.155213 0)
			(layer "B.Fab")
			(effects
				(font
					(size 0.7 0.7)
					(thickness 0.15)
				)
				(justify left bottom mirror)
			)
		)
		(property "Datasheet" "https://www.murata.com/products/productdetail?partno=GRM155R61E105KE11%23"
			(at 0 0 0)
			(layer "B.Fab")
			(hide yes)
			(effects
				(font
					(size 1.27 1.27)
					(thickness 0.15)
				)
				(justify mirror)
			)
		)
		(property "Description" "SMD Multilayer Ceramic Capacitor, 1 µF, 25 V, 0402 [1005 Metric], ± 10%, X5R, GRM Series"
			(at 0 0 0)
			(layer "B.Fab")
			(hide yes)
			(effects
				(font
					(size 1.27 1.27)
					(thickness 0.15)
				)
				(justify mirror)
			)
		)
		(property "MPN" "GRM155R61E105KE11J"
			(at 0 0 180)
			(unlocked yes)
			(layer "B.Fab")
			(hide yes)
			(effects
				(font
					(size 1 1)
					(thickness 0.15)
				)
				(justify mirror)
			)
		)
		(property "Manufacturer" "Murata"
			(at 0 0 180)
			(unlocked yes)
			(layer "B.Fab")
			(hide yes)
			(effects
				(font
					(size 1 1)
					(thickness 0.15)
				)
				(justify mirror)
			)
		)
		(property "License" "Apache-2.0"
			(at 0 0 180)
			(unlocked yes)
			(layer "B.Fab")
			(hide yes)
			(effects
				(font
					(size 1 1)
					(thickness 0.15)
				)
				(justify mirror)
			)
		)
		(property "Author" "Antmicro"
			(at 0 0 180)
			(unlocked yes)
			(layer "B.Fab")
			(hide yes)
			(effects
				(font
					(size 1 1)
					(thickness 0.15)
				)
				(justify mirror)
			)
		)
		(property "Val" "1u"
			(at 0 0 180)
			(unlocked yes)
			(layer "B.Fab")
			(hide yes)
			(effects
				(font
					(size 1 1)
					(thickness 0.15)
				)
				(justify mirror)
			)
		)
		(property "Voltage" "25V"
			(at 0 0 180)
			(unlocked yes)
			(layer "B.Fab")
			(hide yes)
			(effects
				(font
					(size 1 1)
					(thickness 0.15)
				)
				(justify mirror)
			)
		)
		(property "Dielectric" "X5R"
			(at 0 0 180)
			(unlocked yes)
			(layer "B.Fab")
			(hide yes)
			(effects
				(font
					(size 1 1)
					(thickness 0.15)
				)
				(justify mirror)
			)
		)
		(sheetname "/X710-AT2 power/")
		(sheetfile "x710-at2-power.kicad_sch")
		(attr smd)
		(fp_rect
			(start -0.925 0.47)
			(end 0.925 -0.47)
			(stroke
				(width 0.05)
				(type default)
			)
			(fill no)
			(layer "B.CrtYd")
		)
		(fp_line
			(start 0.504 0.25)
			(end 0.504 -0.248)
			(stroke
				(width 0.15)
				(type solid)
			)
			(layer "B.Fab")
		)
		(fp_line
			(start 0.504 -0.248)
			(end -0.494 -0.248)
			(stroke
				(width 0.15)
				(type solid)
			)
			(layer "B.Fab")
		)
		(fp_line
			(start -0.494 0.25)
			(end 0.504 0.25)
			(stroke
				(width 0.15)
				(type solid)
			)
			(layer "B.Fab")
		)
		(fp_line
			(start -0.494 -0.248)
			(end -0.494 0.25)
			(stroke
				(width 0.15)
				(type solid)
			)
			(layer "B.Fab")
		)
		(fp_text user "Author: Antmicro"
			(at -0.939 -3.399 0)
			(layer "B.Fab")
			(effects
				(font
					(size 0.7 0.7)
					(thickness 0.15)
				)
				(justify left bottom mirror)
			)
		)
		(fp_text user "License: Apache-2.0"
			(at -0.939 -5.799 0)
			(layer "B.Fab")
			(effects
				(font
					(size 0.7 0.7)
					(thickness 0.15)
				)
				(justify left bottom mirror)
			)
		)
		(fp_text user "${REFERENCE}"
			(at -0.939 -4.599 0)
			(layer "B.Fab")
			(effects
				(font
					(size 0.7 0.7)
					(thickness 0.15)
				)
				(justify left bottom mirror)
			)
		)
		(pad "1" smd roundrect
			(at -0.48 0 180)
			(size 0.59 0.64)
			(layers "B.Cu" "B.Mask" "B.Paste")
			(roundrect_rratio 0.25)
			(net 23 "GND")
			(pintype "passive")
		)
		(pad "2" smd roundrect
			(at 0.48 0 180)
			(size 0.59 0.64)
			(layers "B.Cu" "B.Mask" "B.Paste")
			(roundrect_rratio 0.25)
			(net 10 "AVDDH")
			(pintype "passive")
		)
	)
	(footprint "antmicro-footprints:R_0402_1005Metric"
		(layer "B.Cu")
		(at 147.531866 69.535117 180)
		(descr "Resistor SMD 0402")
		(tags "resistor SMD 0402")
		(property "Reference" "R160"
			(at -19.068134 -9.464883 0)
			(layer "B.SilkS")
			(effects
				(font
					(size 0.7 0.7)
					(thickness 0.15)
				)
				(justify mirror)
			)
		)
		(property "Value" "R_100R_0402"
			(at -1.011843 -1.772047 0)
			(layer "B.Fab")
			(effects
				(font
					(size 0.7 0.7)
					(thickness 0.15)
				)
				(justify left bottom mirror)
			)
		)
		(property "Datasheet" "https://www.bourns.com/docs/product-datasheets/cr.pdf"
			(at 0 0 0)
			(layer "B.Fab")
			(hide yes)
			(effects
				(font
					(size 1.27 1.27)
					(thickness 0.15)
				)
				(justify mirror)
			)
		)
		(property "Description" "SMD Chip Resistor, 100 ohm, ± 1%, 62.5 mW, 0402 [1005 Metric], Thick Film, General Purpose"
			(at 0 0 0)
			(layer "B.Fab")
			(hide yes)
			(effects
				(font
					(size 1.27 1.27)
					(thickness 0.15)
				)
				(justify mirror)
			)
		)
		(property "MPN" "CR0402-FX-1000GLF"
			(at 0 0 180)
			(unlocked yes)
			(layer "B.Fab")
			(hide yes)
			(effects
				(font
					(size 1 1)
					(thickness 0.15)
				)
				(justify mirror)
			)
		)
		(property "Manufacturer" "Bourns"
			(at 0 0 180)
			(unlocked yes)
			(layer "B.Fab")
			(hide yes)
			(effects
				(font
					(size 1 1)
					(thickness 0.15)
				)
				(justify mirror)
			)
		)
		(property "License" "Apache-2.0"
			(at 0 0 180)
			(unlocked yes)
			(layer "B.Fab")
			(hide yes)
			(effects
				(font
					(size 1 1)
					(thickness 0.15)
				)
				(justify mirror)
			)
		)
		(property "Author" "Antmicro"
			(at 0 0 180)
			(unlocked yes)
			(layer "B.Fab")
			(hide yes)
			(effects
				(font
					(size 1 1)
					(thickness 0.15)
				)
				(justify mirror)
			)
		)
		(property "Val" "100R"
			(at 0 0 180)
			(unlocked yes)
			(layer "B.Fab")
			(hide yes)
			(effects
				(font
					(size 1 1)
					(thickness 0.15)
				)
				(justify mirror)
			)
		)
		(property "Tolerance" "1%"
			(at 0 0 180)
			(unlocked yes)
			(layer "B.Fab")
			(hide yes)
			(effects
				(font
					(size 1 1)
					(thickness 0.15)
				)
				(justify mirror)
			)
		)
		(sheetname "/X710-AT2 Misc/")
		(sheetfile "x710-at2-mics.kicad_sch")
		(attr smd dnp)
		(fp_rect
			(start -0.925 0.47)
			(end 0.925 -0.47)
			(stroke
				(width 0.05)
				(type default)
			)
			(fill no)
			(layer "B.CrtYd")
		)
		(fp_rect
			(start -0.5 0.25)
			(end 0.5 -0.25)
			(stroke
				(width 0.15)
				(type solid)
			)
			(fill no)
			(layer "B.Fab")
		)
		(fp_text user "License: Apache-2.0"
			(at -0.95 -5.169 0)
			(layer "B.Fab")
			(effects
				(font
					(size 0.7 0.7)
					(thickness 0.15)
				)
				(justify left bottom mirror)
			)
		)
		(fp_text user "${REFERENCE}"
			(at -0.95 -3.168 0)
			(layer "B.Fab")
			(effects
				(font
					(size 0.7 0.7)
					(thickness 0.15)
				)
				(justify left bottom mirror)
			)
		)
		(fp_text user "Author: Antmicro"
			(at -0.95 -4.169 0)
			(layer "B.Fab")
			(effects
				(font
					(size 0.7 0.7)
					(thickness 0.15)
				)
				(justify left bottom mirror)
			)
		)
		(pad "1" smd roundrect
			(at -0.48 0 180)
			(size 0.59 0.64)
			(layers "B.Cu" "B.Mask" "B.Paste")
			(roundrect_rratio 0.25)
			(net 23 "GND")
			(pintype "passive")
		)
		(pad "2" smd roundrect
			(at 0.48 0 180)
			(size 0.59 0.64)
			(layers "B.Cu" "B.Mask" "B.Paste")
			(roundrect_rratio 0.25)
			(net 126 "/X710-AT2 Misc/~{PCI_DIS}")
			(pintype "passive")
		)
	)
	(footprint "antmicro-footprints:R_0402_1005Metric"
		(layer "B.Cu")
		(at 140.4 134.6)
		(descr "Resistor SMD 0402")
		(tags "resistor SMD 0402")
		(property "Reference" "R24"
			(at 19.525001 -8.1 180)
			(layer "B.SilkS")
			(effects
				(font
					(size 0.7 0.7)
					(thickness 0.15)
				)
				(justify mirror)
			)
		)
		(property "Value" "R_100k_0402"
			(at -1.011843 -1.772047 180)
			(layer "B.Fab")
			(effects
				(font
					(size 0.7 0.7)
					(thickness 0.15)
				)
				(justify left bottom mirror)
			)
		)
		(property "Datasheet" "https://www.bourns.com/docs/product-datasheets/cr.pdf"
			(at 0 0 180)
			(layer "B.Fab")
			(hide yes)
			(effects
				(font
					(size 1.27 1.27)
					(thickness 0.15)
				)
				(justify mirror)
			)
		)
		(property "Description" "SMD Chip Resistor, 100 kohm, ± 1%, 62.5 mW, 0402 [1005 Metric], Thick Film, General Purpose"
			(at 0 0 180)
			(layer "B.Fab")
			(hide yes)
			(effects
				(font
					(size 1.27 1.27)
					(thickness 0.15)
				)
				(justify mirror)
			)
		)
		(property "MPN" "CR0402-FX-1003GLF"
			(at 0 0 0)
			(unlocked yes)
			(layer "B.Fab")
			(hide yes)
			(effects
				(font
					(size 1 1)
					(thickness 0.15)
				)
				(justify mirror)
			)
		)
		(property "Manufacturer" "Bourns"
			(at 0 0 0)
			(unlocked yes)
			(layer "B.Fab")
			(hide yes)
			(effects
				(font
					(size 1 1)
					(thickness 0.15)
				)
				(justify mirror)
			)
		)
		(property "License" "Apache-2.0"
			(at 0 0 0)
			(unlocked yes)
			(layer "B.Fab")
			(hide yes)
			(effects
				(font
					(size 1 1)
					(thickness 0.15)
				)
				(justify mirror)
			)
		)
		(property "Val" "100k"
			(at 0 0 0)
			(unlocked yes)
			(layer "B.Fab")
			(hide yes)
			(effects
				(font
					(size 1 1)
					(thickness 0.15)
				)
				(justify mirror)
			)
		)
		(property "Tolerance" "1%"
			(at 0 0 0)
			(unlocked yes)
			(layer "B.Fab")
			(hide yes)
			(effects
				(font
					(size 1 1)
					(thickness 0.15)
				)
				(justify mirror)
			)
		)
		(property "Author" "Antmicro"
			(at 0 0 0)
			(unlocked yes)
			(layer "B.Fab")
			(hide yes)
			(effects
				(font
					(size 1 1)
					(thickness 0.15)
				)
				(justify mirror)
			)
		)
		(sheetname "/PD and TB DC-DC/")
		(sheetfile "PD_and_TB_DC_DC.kicad_sch")
		(attr smd)
		(fp_rect
			(start -0.925 0.47)
			(end 0.925 -0.47)
			(stroke
				(width 0.05)
				(type default)
			)
			(fill no)
			(layer "B.CrtYd")
		)
		(fp_rect
			(start -0.5 0.25)
			(end 0.5 -0.25)
			(stroke
				(width 0.15)
				(type solid)
			)
			(fill no)
			(layer "B.Fab")
		)
		(fp_text user "${REFERENCE}"
			(at -0.95 -3.168 180)
			(layer "B.Fab")
			(effects
				(font
					(size 0.7 0.7)
					(thickness 0.15)
				)
				(justify left bottom mirror)
			)
		)
		(fp_text user "Author: Antmicro"
			(at -0.95 -4.169 180)
			(layer "B.Fab")
			(effects
				(font
					(size 0.7 0.7)
					(thickness 0.15)
				)
				(justify left bottom mirror)
			)
		)
		(fp_text user "License: Apache-2.0"
			(at -0.95 -5.169 180)
			(layer "B.Fab")
			(effects
				(font
					(size 0.7 0.7)
					(thickness 0.15)
				)
				(justify left bottom mirror)
			)
		)
		(pad "1" smd roundrect
			(at -0.48 0)
			(size 0.59 0.64)
			(layers "B.Cu" "B.Mask" "B.Paste")
			(roundrect_rratio 0.25)
			(net 207 "Net-(U3-DEBUG_CTL1(GPIO16,_I2CADDR_B4))")
			(pintype "passive")
		)
		(pad "2" smd roundrect
			(at 0.48 0)
			(size 0.59 0.64)
			(layers "B.Cu" "B.Mask" "B.Paste")
			(roundrect_rratio 0.25)
			(net 304 "/PD and TB DC-DC/TPS_3V3")
			(pintype "passive")
		)
	)
	(footprint "antmicro-footprints:C_0402_1005Metric"
		(layer "B.Cu")
		(at 149.58 146.66 -90)
		(descr "Capacitor SMD 0402")
		(tags "capacitor SMD 0402")
		(property "Reference" "C306"
			(at 1.09 -0.42 90)
			(layer "B.SilkS")
			(effects
				(font
					(size 0.7 0.7)
					(thickness 0.15)
				)
				(justify left bottom mirror)
			)
		)
		(property "Value" "C_470p_0402"
			(at -1.022927 -2.155213 90)
			(layer "B.Fab")
			(effects
				(font
					(size 0.7 0.7)
					(thickness 0.15)
				)
				(justify left bottom mirror)
			)
		)
		(property "Datasheet" "https://www.passivecomponent.com/wp-content/uploads/datasheet/WTC_MLCC_General_Purpose.pdf"
			(at 0 0 90)
			(layer "B.Fab")
			(hide yes)
			(effects
				(font
					(size 1.27 1.27)
					(thickness 0.15)
				)
				(justify mirror)
			)
		)
		(property "Description" "SMD Multilayer Ceramic Capacitor, General Purpose, 470 pF, 25 V, 0402 [1005 Metric], ± 10%, X7R"
			(at 0 0 90)
			(layer "B.Fab")
			(hide yes)
			(effects
				(font
					(size 1.27 1.27)
					(thickness 0.15)
				)
				(justify mirror)
			)
		)
		(property "MPN" "0402B471K250CT"
			(at 0 0 270)
			(unlocked yes)
			(layer "B.Fab")
			(hide yes)
			(effects
				(font
					(size 1 1)
					(thickness 0.15)
				)
				(justify mirror)
			)
		)
		(property "Manufacturer" "Walsin"
			(at 0 0 270)
			(unlocked yes)
			(layer "B.Fab")
			(hide yes)
			(effects
				(font
					(size 1 1)
					(thickness 0.15)
				)
				(justify mirror)
			)
		)
		(property "License" "Apache-2.0"
			(at 0 0 270)
			(unlocked yes)
			(layer "B.Fab")
			(hide yes)
			(effects
				(font
					(size 1 1)
					(thickness 0.15)
				)
				(justify mirror)
			)
		)
		(property "Author" "Antmicro"
			(at 0 0 270)
			(unlocked yes)
			(layer "B.Fab")
			(hide yes)
			(effects
				(font
					(size 1 1)
					(thickness 0.15)
				)
				(justify mirror)
			)
		)
		(property "Val" "470p"
			(at 0 0 270)
			(unlocked yes)
			(layer "B.Fab")
			(hide yes)
			(effects
				(font
					(size 1 1)
					(thickness 0.15)
				)
				(justify mirror)
			)
		)
		(property "Voltage" "25V"
			(at 0 0 270)
			(unlocked yes)
			(layer "B.Fab")
			(hide yes)
			(effects
				(font
					(size 1 1)
					(thickness 0.15)
				)
				(justify mirror)
			)
		)
		(property "Dielectric" "X7R"
			(at 0 0 270)
			(unlocked yes)
			(layer "B.Fab")
			(hide yes)
			(effects
				(font
					(size 1 1)
					(thickness 0.15)
				)
				(justify mirror)
			)
		)
		(sheetname "/2xRJ45/")
		(sheetfile "2xrj45.kicad_sch")
		(attr smd)
		(fp_rect
			(start -0.925 0.47)
			(end 0.925 -0.47)
			(stroke
				(width 0.05)
				(type default)
			)
			(fill no)
			(layer "B.CrtYd")
		)
		(fp_line
			(start -0.494 0.25)
			(end 0.504 0.25)
			(stroke
				(width 0.15)
				(type solid)
			)
			(layer "B.Fab")
		)
		(fp_line
			(start 0.504 0.25)
			(end 0.504 -0.248)
			(stroke
				(width 0.15)
				(type solid)
			)
			(layer "B.Fab")
		)
		(fp_line
			(start -0.494 -0.248)
			(end -0.494 0.25)
			(stroke
				(width 0.15)
				(type solid)
			)
			(layer "B.Fab")
		)
		(fp_line
			(start 0.504 -0.248)
			(end -0.494 -0.248)
			(stroke
				(width 0.15)
				(type solid)
			)
			(layer "B.Fab")
		)
		(fp_text user "Author: Antmicro"
			(at -0.939 -3.399 90)
			(layer "B.Fab")
			(effects
				(font
					(size 0.7 0.7)
					(thickness 0.15)
				)
				(justify left bottom mirror)
			)
		)
		(fp_text user "License: Apache-2.0"
			(at -0.939 -5.799 90)
			(layer "B.Fab")
			(effects
				(font
					(size 0.7 0.7)
					(thickness 0.15)
				)
				(justify left bottom mirror)
			)
		)
		(fp_text user "${REFERENCE}"
			(at -0.939 -4.599 90)
			(layer "B.Fab")
			(effects
				(font
					(size 0.7 0.7)
					(thickness 0.15)
				)
				(justify left bottom mirror)
			)
		)
		(pad "1" smd roundrect
			(at -0.48 0 270)
			(size 0.59 0.64)
			(layers "B.Cu" "B.Mask" "B.Paste")
			(roundrect_rratio 0.25)
			(net 23 "GND")
			(pintype "passive")
		)
		(pad "2" smd roundrect
			(at 0.48 0 270)
			(size 0.59 0.64)
			(layers "B.Cu" "B.Mask" "B.Paste")
			(roundrect_rratio 0.25)
			(net 410 "Net-(J3-LED_GRN-)")
			(pintype "passive")
		)
	)
)
